FILE_TYPE = MULTI_PHYS_TABLE;

PART 'SN74LVC1G11DCKR'

{========================================================================================}
:VALUE             | PART_TYPE | MATERIAL | PART_NUMBER    = STANDARD    | LIFECYCLE      | PART_NUMBER   | JEDEC_TYPE           | DESCRIPTION                         | MANUFTR | MANUF_PN          | RD_CMPLS_LVL | CMPLS_LVL | FROM_PJ           | CLASS | DIP_SMD | DATA                      | EE_CHECK_LIST | FP_ECN | PSL | CREATOR | STATUS | MSD  | ESD_CDM | ESD_HBM | ESD_MM | PIN_LENGTH_SHORT_PIN | PIN_LENGTH_LONG_PIN | CREATEDAY  ;
{========================================================================================}
 'SN74LVC1G11DCKR' | 'SMLF'    | 'IC'     | 'ALLVC1G1000'(!) = 'End of Design'  | 'Comp-Approve'   | 'ALLVC1G1000' |'SC70-6_0-65_2X1-25'| 'IC OTHER(6P)SN74LVC1G11DCKR(SC70)' | 'TIC'   | 'SN74LVC1G11DCKR' | 'EP(V1)'     | 'EP(V1)'  | 'ALVIN TEMP-OWEN' | 'IC'  | ''      | 'TIC_SN74LVC1G11DCKR.pdf' | ''            | ''     | ''  | ''      | ''     | 'NA' | '1000V' | '2000V' | 'NA'   | '0 MILS'             | '0 MILS'            | '20201022'
 'SN74LVC1G11DCKR' | 'SMLF'    | 'EMPTY'  | 'ALLVC1G1000'(!) = 'End of Design'  | 'Comp-Approve'   | 'ALLVC1G1000' |'SC70-6_0-65_2X1-25'| 'IC OTHER(6P)SN74LVC1G11DCKR(SC70)' | 'TIC'   | 'SN74LVC1G11DCKR' | 'EP(V1)'     | 'EP(V1)'  | 'ALVIN TEMP-OWEN' | 'IC'  | ''      | 'TIC_SN74LVC1G11DCKR.pdf' | ''            | ''     | ''  | ''      | ''     | 'NA' | '1000V' | '2000V' | 'NA'   | '0 MILS'             | '0 MILS'            | '20201022'

END_PART

END.

